(kicad_pcb
	(version 20260206)
	(generator "pcbnew")
	(generator_version "10.0")
	(general
		(thickness 1.6)
		(legacy_teardrops no)
	)
	(paper "A4")
	(title_block
		(title "panther-plus-userver — 13130-1b_20150205.brd")
		(comment 1 "Honey Badger (Wiwynn) / footprints 292-299 of 1509")
	)
	(layers
		(0 "F.Cu" signal "TOP")
		(4 "In1.Cu" signal "L2")
		(6 "In2.Cu" signal "L3")
		(8 "In3.Cu" signal "L4")
		(10 "In4.Cu" signal "L5")
		(12 "In5.Cu" signal "L6")
		(14 "In6.Cu" signal "L7")
		(16 "In7.Cu" signal "L8")
		(18 "In8.Cu" signal "L9")
		(20 "In9.Cu" signal "L10")
		(22 "In10.Cu" signal "L11")
		(2 "B.Cu" signal "BOTTOM")
		(9 "F.Adhes" user "F.Adhesive")
		(11 "B.Adhes" user "B.Adhesive")
		(13 "F.Paste" user "Package Geometry/Pastemask Top")
		(15 "B.Paste" user "Package Geometry/Pastemask Bottom")
		(5 "F.SilkS" user "Ref Des/Silkscreen Top")
		(7 "B.SilkS" user "Ref Des/Silkscreen Bottom")
		(1 "F.Mask" user "Board Geometry/Soldermask Top")
		(3 "B.Mask" user "Board Geometry/Soldermask Bottom")
		(17 "Dwgs.User" user "User.Drawings")
		(19 "Cmts.User" user "User.Comments")
		(21 "Eco1.User" user "User.Eco1")
		(23 "Eco2.User" user "User.Eco2")
		(25 "Edge.Cuts" user "Board Geometry/Outline")
		(27 "Margin" user)
		(31 "F.CrtYd" user "Package Geometry/Place Bound Top")
		(29 "B.CrtYd" user "Package Geometry/Place Bound Bottom")
		(35 "F.Fab" user "Ref Des/Assembly Top")
		(33 "B.Fab" user "Ref Des/Assembly Bottom")
	)
	(footprint ""
		(layer "F.Cu")
		(at 34.7472 -65.659 180)
		(property "Reference" "PQ1"
			(at 0 0 180)
			(layer "F.SilkS")
			(hide yes)
			(effects
				(font
					(size 1.27 1.27)
				)
			)
		)
		(property "Value" "FDMC8200-GP"
			(at -4.6736 -4.6228 180)
			(unlocked yes)
			(layer "F.Fab")
			(hide yes)
			(effects
				(font
					(size 1.016 1.016)
					(thickness 0.1524)
				)
			)
		)
		(property "Device Type" "MLP8F3-G2P-1H32"
			(at -4.6736 -6.1468 180)
			(unlocked yes)
			(layer "F.Fab")
			(hide yes)
			(effects
				(font
					(size 1.016 1.016)
					(thickness 0.1524)
				)
			)
		)
		(duplicate_pad_numbers_are_jumpers no)
		(fp_poly
			(pts
				(xy 0.430784 -2.553208) (xy 1.49987 -2.553208) (xy 0.9652 -2.018792)
			)
			(stroke
				(width 0)
				(type default)
			)
			(fill yes)
			(layer "F.SilkS")
		)
		(fp_rect
			(start -1.7526 2.0066)
			(end 1.7526 -2.0066)
			(stroke
				(width 0)
				(type default)
			)
			(fill no)
			(layer "F.CrtYd")
		)
		(fp_rect
			(start -1.7526 2.0066)
			(end 1.7526 -2.0066)
			(stroke
				(width 0)
				(type default)
			)
			(fill no)
			(layer "F.Fab")
		)
		(pad "1" smd rect
			(at 0.975106 -1.524 180)
			(size 0.4064 0.7112)
			(layers "F.Cu" "F.Mask" "F.Paste")
			(net "VR_PVNN_GH_R")
		)
		(pad "2" smd rect
			(at 0.32512 -1.524 180)
			(size 0.4064 0.7112)
			(layers "F.Cu" "F.Mask" "F.Paste")
			(net "VR_FET_SW_P12V_PVCCP_PVNN")
		)
		(pad "3" smd rect
			(at -0.32512 -1.524 180)
			(size 0.4064 0.7112)
			(layers "F.Cu" "F.Mask" "F.Paste")
			(net "VR_FET_SW_P12V_PVCCP_PVNN")
		)
		(pad "4" smd rect
			(at -0.975106 -1.524 180)
			(size 0.4064 0.7112)
			(layers "F.Cu" "F.Mask" "F.Paste")
			(net "VR_FET_SW_P12V_PVCCP_PVNN")
		)
		(pad "5" smd rect
			(at -0.975106 1.524 180)
			(size 0.4064 0.7112)
			(layers "F.Cu" "F.Mask" "F.Paste")
			(net "GND")
		)
		(pad "6" smd rect
			(at -0.32512 1.524 180)
			(size 0.4064 0.7112)
			(layers "F.Cu" "F.Mask" "F.Paste")
			(net "GND")
		)
		(pad "7" smd rect
			(at 0.32512 1.524 180)
			(size 0.4064 0.7112)
			(layers "F.Cu" "F.Mask" "F.Paste")
			(net "GND")
		)
		(pad "8" smd rect
			(at 0.975106 1.524 180)
			(size 0.4064 0.7112)
			(layers "F.Cu" "F.Mask" "F.Paste")
			(net "VR_PVNN_LH_R")
		)
		(pad "9" smd rect
			(at 0 -0.670306 180)
			(size 2.4384 0.5588)
			(layers "F.Cu" "F.Mask" "F.Paste")
			(net "VR_FET_SW_P12V_PVCCP_PVNN")
		)
		(pad "10" smd rect
			(at 0 0.429006 180)
			(size 2.4384 1.0414)
			(layers "F.Cu" "F.Mask" "F.Paste")
			(net "VR_PVNN_PHASE")
		)
	)
	(footprint ""
		(layer "F.Cu")
		(at 203.4794 -58.2676 90)
		(property "Reference" "PC170"
			(at 0 0 90)
			(layer "F.SilkS")
			(hide yes)
			(effects
				(font
					(size 1.27 1.27)
				)
			)
		)
		(property "Value" "SC22U6D3V5MX-2GP"
			(at 0 -4.9022 90)
			(unlocked yes)
			(layer "F.Fab")
			(hide yes)
			(effects
				(font
					(size 1.016 1.016)
					(thickness 0.1524)
				)
			)
		)
		(property "Device Type" "C805H58"
			(at 0 -6.8072 90)
			(unlocked yes)
			(layer "F.Fab")
			(hide yes)
			(effects
				(font
					(size 1.016 1.016)
					(thickness 0.1524)
				)
			)
		)
		(duplicate_pad_numbers_are_jumpers no)
		(fp_line
			(start 0.6096 0)
			(end -0.6096 0)
			(stroke
				(width 0.3048)
				(type default)
			)
			(layer "F.SilkS")
		)
		(fp_poly
			(pts
				(xy -0.9017 1.4351) (xy 0.9017 1.4351) (xy 0.9017 -1.4351) (xy -0.9017 -1.4351)
			)
			(stroke
				(width 0)
				(type default)
			)
			(fill no)
			(layer "F.CrtYd")
		)
		(fp_poly
			(pts
				(xy 0.9017 1.4351) (xy 0.9017 -1.4351) (xy -0.9017 -1.4351) (xy -0.9017 1.4351)
			)
			(stroke
				(width 0)
				(type default)
			)
			(fill no)
			(layer "F.Fab")
		)
		(pad "1" smd rect
			(at 0 -0.8382 90)
			(size 1.5494 0.9398)
			(layers "F.Cu" "F.Mask" "F.Paste")
			(net "PV_VDDR")
		)
		(pad "2" smd rect
			(at 0 0.8382 90)
			(size 1.5494 0.9398)
			(layers "F.Cu" "F.Mask" "F.Paste")
			(net "GND")
		)
	)
	(footprint ""
		(layer "F.Cu")
		(at 23.38324 -68.6562 90)
		(property "Reference" "PD1"
			(at 0 0 90)
			(layer "F.SilkS")
			(hide yes)
			(effects
				(font
					(size 1.27 1.27)
				)
			)
		)
		(property "Value" "MM3Z5V6T1G-GP"
			(at 2.5527 -1.9812 90)
			(unlocked yes)
			(layer "F.Fab")
			(hide yes)
			(effects
				(font
					(size 1.016 1.016)
					(thickness 0.1524)
				)
			)
		)
		(property "Device Type" "SOD323AKH40"
			(at 2.5527 -3.5052 90)
			(unlocked yes)
			(layer "F.Fab")
			(hide yes)
			(effects
				(font
					(size 1.016 1.016)
					(thickness 0.1524)
				)
			)
		)
		(duplicate_pad_numbers_are_jumpers no)
		(fp_line
			(start 0.7747 1.7653)
			(end -0.7747 1.7653)
			(stroke
				(width 0.254)
				(type default)
			)
			(layer "F.SilkS")
		)
		(fp_rect
			(start -0.9017 1.6383)
			(end 0.9017 -1.6383)
			(stroke
				(width 0)
				(type default)
			)
			(fill no)
			(layer "F.CrtYd")
		)
		(fp_rect
			(start -0.9017 1.6383)
			(end 0.9017 -1.6383)
			(stroke
				(width 0)
				(type default)
			)
			(fill no)
			(layer "F.Fab")
		)
		(pad "A" smd rect
			(at 0 -1.100074 90)
			(size 0.5588 0.8128)
			(layers "F.Cu" "F.Mask" "F.Paste")
			(net "GND")
		)
		(pad "K" smd rect
			(at 0 1.100074 90)
			(size 0.5588 0.8128)
			(layers "F.Cu" "F.Mask" "F.Paste")
			(net "VCCP_Z")
		)
	)
	(footprint ""
		(layer "F.Cu")
		(at 40.132 -38.6588 90)
		(property "Reference" "R251"
			(at 0 0 90)
			(layer "F.SilkS")
			(hide yes)
			(effects
				(font
					(size 1.27 1.27)
				)
			)
		)
		(property "Value" "51R2F-2-GP"
			(at 0.064008 -3.993896 90)
			(unlocked yes)
			(layer "F.Fab")
			(hide yes)
			(effects
				(font
					(size 1.016 1.016)
					(thickness 0.1524)
				)
			)
		)
		(property "Device Type" "R402H16"
			(at 0.064008 -5.517896 90)
			(unlocked yes)
			(layer "F.Fab")
			(hide yes)
			(effects
				(font
					(size 1.016 1.016)
					(thickness 0.1524)
				)
			)
		)
		(duplicate_pad_numbers_are_jumpers no)
		(fp_rect
			(start -0.381 0.8382)
			(end 0.381 -0.8382)
			(stroke
				(width 0)
				(type default)
			)
			(fill no)
			(layer "F.CrtYd")
		)
		(fp_rect
			(start -0.381 0.8382)
			(end 0.381 -0.8382)
			(stroke
				(width 0)
				(type default)
			)
			(fill no)
			(layer "F.Fab")
		)
		(pad "1" smd custom
			(at 0 -0.4318 90)
			(size 0.127 0.127)
			(layers "F.Cu" "F.Mask" "F.Paste")
			(net "XDP_SOC_CPU_TCK")
			(options
				(clearance outline)
				(anchor circle)
			)
			(primitives
				(gr_poly
					(pts
						(arc
							(start -0.2032 -0.2794)
							(mid -0.239121 -0.264521)
							(end -0.254 -0.2286)
						)
						(arc
							(start -0.254 0.2286)
							(mid -0.239121 0.264521)
							(end -0.2032 0.2794)
						)
						(arc
							(start 0.2032 0.2794)
							(mid 0.239121 0.264521)
							(end 0.254 0.2286)
						)
						(arc
							(start 0.254 -0.2286)
							(mid 0.239121 -0.264521)
							(end 0.2032 -0.2794)
						)
					)
					(width 0)
					(fill yes)
				)
			)
		)
		(pad "2" smd custom
			(at 0 0.4318 90)
			(size 0.127 0.127)
			(layers "F.Cu" "F.Mask" "F.Paste")
			(net "GND")
			(options
				(clearance outline)
				(anchor circle)
			)
			(primitives
				(gr_poly
					(pts
						(arc
							(start -0.2032 -0.2794)
							(mid -0.239121 -0.264521)
							(end -0.254 -0.2286)
						)
						(arc
							(start -0.254 0.2286)
							(mid -0.239121 0.264521)
							(end -0.2032 0.2794)
						)
						(arc
							(start 0.2032 0.2794)
							(mid 0.239121 0.264521)
							(end 0.254 0.2286)
						)
						(arc
							(start 0.254 -0.2286)
							(mid 0.239121 -0.264521)
							(end 0.2032 -0.2794)
						)
					)
					(width 0)
					(fill yes)
				)
			)
		)
	)
	(footprint ""
		(layer "F.Cu")
		(at 24.3586 -51.3588)
		(property "Reference" "PR77"
			(at 0 0 0)
			(layer "F.SilkS")
			(hide yes)
			(effects
				(font
					(size 1.27 1.27)
				)
			)
		)
		(property "Value" "180R2F-1-GP"
			(at 1.7907 -1.1176 0)
			(unlocked yes)
			(layer "F.Fab")
			(hide yes)
			(effects
				(font
					(size 1.016 1.016)
					(thickness 0.1524)
				)
			)
		)
		(property "Device Type" "R402H16"
			(at 1.7907 -2.6416 0)
			(unlocked yes)
			(layer "F.Fab")
			(hide yes)
			(effects
				(font
					(size 1.016 1.016)
					(thickness 0.1524)
				)
			)
		)
		(duplicate_pad_numbers_are_jumpers no)
		(fp_rect
			(start -0.381 0.8382)
			(end 0.381 -0.8382)
			(stroke
				(width 0)
				(type default)
			)
			(fill no)
			(layer "F.CrtYd")
		)
		(fp_rect
			(start -0.381 0.8382)
			(end 0.381 -0.8382)
			(stroke
				(width 0)
				(type default)
			)
			(fill no)
			(layer "F.Fab")
		)
		(pad "1" smd custom
			(at 0 -0.4318)
			(size 0.127 0.127)
			(layers "F.Cu" "F.Mask" "F.Paste")
			(net "VR_PVCCP_ISUMN_R")
			(options
				(clearance outline)
				(anchor circle)
			)
			(primitives
				(gr_poly
					(pts
						(arc
							(start -0.2032 -0.2794)
							(mid -0.239121 -0.264521)
							(end -0.254 -0.2286)
						)
						(arc
							(start -0.254 0.2286)
							(mid -0.239121 0.264521)
							(end -0.2032 0.2794)
						)
						(arc
							(start 0.2032 0.2794)
							(mid 0.239121 0.264521)
							(end 0.254 0.2286)
						)
						(arc
							(start 0.254 -0.2286)
							(mid 0.239121 -0.264521)
							(end 0.2032 -0.2794)
						)
					)
					(width 0)
					(fill yes)
				)
			)
		)
		(pad "2" smd custom
			(at 0 0.4318)
			(size 0.127 0.127)
			(layers "F.Cu" "F.Mask" "F.Paste")
			(net "VR_PVCCP_ISUMN")
			(options
				(clearance outline)
				(anchor circle)
			)
			(primitives
				(gr_poly
					(pts
						(arc
							(start -0.2032 -0.2794)
							(mid -0.239121 -0.264521)
							(end -0.254 -0.2286)
						)
						(arc
							(start -0.254 0.2286)
							(mid -0.239121 0.264521)
							(end -0.2032 0.2794)
						)
						(arc
							(start 0.2032 0.2794)
							(mid 0.239121 0.264521)
							(end 0.254 0.2286)
						)
						(arc
							(start 0.254 -0.2286)
							(mid 0.239121 -0.264521)
							(end 0.2032 -0.2794)
						)
					)
					(width 0)
					(fill yes)
				)
			)
		)
	)
	(footprint ""
		(layer "F.Cu")
		(at 17.272 -50.8 180)
		(property "Reference" "PR188"
			(at 0 0 180)
			(layer "F.SilkS")
			(hide yes)
			(effects
				(font
					(size 1.27 1.27)
				)
			)
		)
		(property "Value" "2K2R2F-GP"
			(at 1.7907 -1.1176 180)
			(unlocked yes)
			(layer "F.Fab")
			(hide yes)
			(effects
				(font
					(size 1.016 1.016)
					(thickness 0.1524)
				)
			)
		)
		(property "Device Type" "R402H16"
			(at 1.7907 -2.6416 180)
			(unlocked yes)
			(layer "F.Fab")
			(hide yes)
			(effects
				(font
					(size 1.016 1.016)
					(thickness 0.1524)
				)
			)
		)
		(duplicate_pad_numbers_are_jumpers no)
		(fp_rect
			(start -0.381 0.8382)
			(end 0.381 -0.8382)
			(stroke
				(width 0)
				(type default)
			)
			(fill no)
			(layer "F.CrtYd")
		)
		(fp_rect
			(start -0.381 0.8382)
			(end 0.381 -0.8382)
			(stroke
				(width 0)
				(type default)
			)
			(fill no)
			(layer "F.Fab")
		)
		(pad "1" smd custom
			(at 0 -0.4318 180)
			(size 0.127 0.127)
			(layers "F.Cu" "F.Mask" "F.Paste")
			(net "VR_PVCCP_COMP_RC")
			(options
				(clearance outline)
				(anchor circle)
			)
			(primitives
				(gr_poly
					(pts
						(arc
							(start -0.2032 -0.2794)
							(mid -0.239121 -0.264521)
							(end -0.254 -0.2286)
						)
						(arc
							(start -0.254 0.2286)
							(mid -0.239121 0.264521)
							(end -0.2032 0.2794)
						)
						(arc
							(start 0.2032 0.2794)
							(mid 0.239121 0.264521)
							(end 0.254 0.2286)
						)
						(arc
							(start 0.254 -0.2286)
							(mid 0.239121 -0.264521)
							(end 0.2032 -0.2794)
						)
					)
					(width 0)
					(fill yes)
				)
			)
		)
		(pad "2" smd custom
			(at 0 0.4318 180)
			(size 0.127 0.127)
			(layers "F.Cu" "F.Mask" "F.Paste")
			(net "VR_PVCCP_FB")
			(options
				(clearance outline)
				(anchor circle)
			)
			(primitives
				(gr_poly
					(pts
						(arc
							(start -0.2032 -0.2794)
							(mid -0.239121 -0.264521)
							(end -0.254 -0.2286)
						)
						(arc
							(start -0.254 0.2286)
							(mid -0.239121 0.264521)
							(end -0.2032 0.2794)
						)
						(arc
							(start 0.2032 0.2794)
							(mid 0.239121 0.264521)
							(end 0.254 0.2286)
						)
						(arc
							(start 0.254 -0.2286)
							(mid 0.239121 -0.264521)
							(end 0.2032 -0.2794)
						)
					)
					(width 0)
					(fill yes)
				)
			)
		)
	)
	(footprint ""
		(layer "F.Cu")
		(at 48.514 -49.149 -90)
		(property "Reference" "C25"
			(at 0 0 270)
			(layer "F.SilkS")
			(hide yes)
			(effects
				(font
					(size 1.27 1.27)
				)
			)
		)
		(property "Value" "SCD1U10V2KX-5GP"
			(at 1.1811 -2.7051 270)
			(unlocked yes)
			(layer "F.Fab")
			(hide yes)
			(effects
				(font
					(size 1.016 1.016)
					(thickness 0.1524)
				)
			)
		)
		(property "Device Type" "C402H22"
			(at 1.1811 -4.2291 270)
			(unlocked yes)
			(layer "F.Fab")
			(hide yes)
			(effects
				(font
					(size 1.016 1.016)
					(thickness 0.1524)
				)
			)
		)
		(duplicate_pad_numbers_are_jumpers no)
		(fp_rect
			(start -0.381 0.7366)
			(end 0.381 -0.7366)
			(stroke
				(width 0)
				(type default)
			)
			(fill no)
			(layer "F.CrtYd")
		)
		(fp_rect
			(start -0.381 0.7366)
			(end 0.381 -0.7366)
			(stroke
				(width 0)
				(type default)
			)
			(fill no)
			(layer "F.Fab")
		)
		(pad "1" smd custom
			(at 0 -0.4572 270)
			(size 0.1143 0.1143)
			(layers "F.Cu" "F.Mask" "F.Paste")
			(net "P1V5_CLK_SCR_LVIO")
			(options
				(clearance outline)
				(anchor circle)
			)
			(primitives
				(gr_poly
					(pts
						(arc
							(start -0.254 -0.1778)
							(mid -0.239121 -0.213721)
							(end -0.2032 -0.2286)
						)
						(arc
							(start 0.2032 -0.2286)
							(mid 0.239121 -0.213721)
							(end 0.254 -0.1778)
						)
						(arc
							(start 0.254 0.1778)
							(mid 0.239121 0.213721)
							(end 0.2032 0.2286)
						)
						(arc
							(start -0.2032 0.2286)
							(mid -0.239121 0.213721)
							(end -0.254 0.1778)
						)
					)
					(width 0)
					(fill yes)
				)
			)
		)
		(pad "2" smd custom
			(at 0 0.4572 270)
			(size 0.1143 0.1143)
			(layers "F.Cu" "F.Mask" "F.Paste")
			(net "GND")
			(options
				(clearance outline)
				(anchor circle)
			)
			(primitives
				(gr_poly
					(pts
						(arc
							(start -0.254 -0.1778)
							(mid -0.239121 -0.213721)
							(end -0.2032 -0.2286)
						)
						(arc
							(start 0.2032 -0.2286)
							(mid 0.239121 -0.213721)
							(end 0.254 -0.1778)
						)
						(arc
							(start 0.254 0.1778)
							(mid 0.239121 0.213721)
							(end 0.2032 0.2286)
						)
						(arc
							(start -0.2032 0.2286)
							(mid -0.239121 0.213721)
							(end -0.254 0.1778)
						)
					)
					(width 0)
					(fill yes)
				)
			)
		)
	)
	(footprint ""
		(layer "F.Cu")
		(at 18.3896 -52.6288 90)
		(property "Reference" "PC72"
			(at 0 0 90)
			(layer "F.SilkS")
			(hide yes)
			(effects
				(font
					(size 1.27 1.27)
				)
			)
		)
		(property "Value" "SC1KP50V2KX-1GP"
			(at 1.8923 -1.2065 90)
			(unlocked yes)
			(layer "F.Fab")
			(hide yes)
			(effects
				(font
					(size 1.016 1.016)
					(thickness 0.1524)
				)
			)
		)
		(property "Device Type" "C402H22"
			(at 1.8923 -2.7305 90)
			(unlocked yes)
			(layer "F.Fab")
			(hide yes)
			(effects
				(font
					(size 1.016 1.016)
					(thickness 0.1524)
				)
			)
		)
		(duplicate_pad_numbers_are_jumpers no)
		(fp_rect
			(start -0.381 0.7366)
			(end 0.381 -0.7366)
			(stroke
				(width 0)
				(type default)
			)
			(fill no)
			(layer "F.CrtYd")
		)
		(fp_rect
			(start -0.381 0.7366)
			(end 0.381 -0.7366)
			(stroke
				(width 0)
				(type default)
			)
			(fill no)
			(layer "F.Fab")
		)
		(pad "1" smd custom
			(at 0 -0.4572 90)
			(size 0.1143 0.1143)
			(layers "F.Cu" "F.Mask" "F.Paste")
			(net "GND")
			(options
				(clearance outline)
				(anchor circle)
			)
			(primitives
				(gr_poly
					(pts
						(arc
							(start -0.254 -0.1778)
							(mid -0.239121 -0.213721)
							(end -0.2032 -0.2286)
						)
						(arc
							(start 0.2032 -0.2286)
							(mid 0.239121 -0.213721)
							(end 0.254 -0.1778)
						)
						(arc
							(start 0.254 0.1778)
							(mid 0.239121 0.213721)
							(end 0.2032 0.2286)
						)
						(arc
							(start -0.2032 0.2286)
							(mid -0.239121 0.213721)
							(end -0.254 0.1778)
						)
					)
					(width 0)
					(fill yes)
				)
			)
		)
		(pad "2" smd custom
			(at 0 0.4572 90)
			(size 0.1143 0.1143)
			(layers "F.Cu" "F.Mask" "F.Paste")
			(net "VR_PVCCP_FB_RC2")
			(options
				(clearance outline)
				(anchor circle)
			)
			(primitives
				(gr_poly
					(pts
						(arc
							(start -0.254 -0.1778)
							(mid -0.239121 -0.213721)
							(end -0.2032 -0.2286)
						)
						(arc
							(start 0.2032 -0.2286)
							(mid 0.239121 -0.213721)
							(end 0.254 -0.1778)
						)
						(arc
							(start 0.254 0.1778)
							(mid 0.239121 0.213721)
							(end 0.2032 0.2286)
						)
						(arc
							(start -0.2032 0.2286)
							(mid -0.239121 0.213721)
							(end -0.254 0.1778)
						)
					)
					(width 0)
					(fill yes)
				)
			)
		)
	)
)
